# BASEBOARD_FAB2 (Tioga Pass) — schematic netlist excerpt (pin names and nets, part order shuffled) for the footprints in the layout excerpt that follows; sources: Cadence DE-HDL packaged netlist, KiCad conversion of Wiwynn_Tioga_Pass_MB.brd

J6M1  SCONN288_H44441003  SCONN  pkg PIP  page 50
  \12v\(1)  = P12V_NVDIMM_DEF
  VSS(93)  = GND
  DQ(4)  = M_D_DQ<4>
  VSS(92)  = GND
  DQ(0)  = M_D_DQ<0>
  VSS(91)  = GND
  DQS9P  = M_D_DQS_DP<9>
  DQS9N  = M_D_DQS_DN<9>
  VSS(90)  = GND
  DQ(6)  = M_D_DQ<6>
  VSS(89)  = GND
  DQ(2)  = M_D_DQ<2>
  VSS(88)  = GND
  DQ(12)  = M_D_DQ<12>
  VSS(87)  = GND
  DQ(8)  = M_D_DQ<8>
  VSS(86)  = GND
  DQS10P  = M_D_DQS_DP<10>
  DQS10N  = M_D_DQS_DN<10>
  VSS(85)  = GND
  DQ(14)  = M_D_DQ<14>
  VSS(84)  = GND
  DQ(10)  = M_D_DQ<10>
  VSS(83)  = GND
  DQ(20)  = M_D_DQ<20>
  VSS(82)  = GND
  DQ(16)  = M_D_DQ<16>
  VSS(81)  = GND
  DQS11P  = M_D_DQS_DP<11>
  DQS11N  = M_D_DQS_DN<11>
  VSS(80)  = GND
  DQ(22)  = M_D_DQ<22>
  VSS(79)  = GND
  DQ(18)  = M_D_DQ<18>
  VSS(78)  = GND
  DQ(28)  = M_D_DQ<28>
  VSS(77)  = GND
  DQ(24)  = M_D_DQ<24>
  VSS(76)  = GND
  DQS12P  = M_D_DQS_DP<12>
  DQS12N  = M_D_DQS_DN<12>
  VSS(75)  = GND
  DQ(30)  = M_D_DQ<30>
  VSS(74)  = GND
  DQ(26)  = M_D_DQ<26>
  VSS(73)  = GND
  CB(4)  = M_D_ECC<4>
  VSS(72)  = GND
  CB(0)  = M_D_ECC<0>
  VSS(71)  = GND
  DQS17P  = M_D_DQS_DP<17>
  DQS17N  = M_D_DQS_DN<17>
  VSS(70)  = GND
  CB(6)  = M_D_ECC<6>
  VSS(69)  = GND
  CB(2)  = M_D_ECC<2>
  VSS(68)  = GND
  RESET_N  = M_DEF_RST_N
  VDD(25)  = PVDDQ_DEF
  CKE(0)  = M_D_CKE<2>
  VDD(24)  = PVDDQ_DEF
  ACT_N  = M_D_ACT_N
  BG(0)  = M_D_BG<0>
  VDD(23)  = PVDDQ_DEF
  A12  = M_D_MA<12>
  A9  = M_D_MA<9>
  VDD(22)  = PVDDQ_DEF
  A8  = M_D_MA<8>
  A6  = M_D_MA<6>
  VDD(21)  = PVDDQ_DEF
  A3  = M_D_MA<3>
  A1  = M_D_MA<1>
  VDD(20)  = PVDDQ_DEF
  CK0P  = M_D_CLK_DP<2>
  CK0N  = M_D_CLK_DN<2>
  VDD(19)  = PVDDQ_DEF
  VTT(1)  = PVTT_DEF
  EVENT_N  = FM_DIMM_EVENT_COD_N
  A0  = M_D_MA<0>
  VDD(18)  = PVDDQ_DEF
  BA(0)  = M_D_BA<0>
  A16_RAS_N  = M_D_MA<16>
  VDD(17)  = PVDDQ_DEF
  S0_N  = M_D_CS_N<4>
  VDD(16)  = PVDDQ_DEF
  A15_CAS_N  = M_D_MA<15>
  ODT(0)  = M_D_ODT<2>
  VDD(15)  = PVDDQ_DEF
  S1_N  = M_D_CS_N<5>
  VDD(14)  = PVDDQ_DEF
  ODT(1)  = M_D_ODT<3>
  VDD(13)  = PVDDQ_DEF
  S2_N_C(0)  = M_D_CS_N<6>
  VSS(67)  = GND
  DQ(36)  = M_D_DQ<36>
  VSS(66)  = GND
  DQ(32)  = M_D_DQ<32>
  VSS(65)  = GND
  DQS13P  = M_D_DQS_DP<13>
  DQS13N  = M_D_DQS_DN<13>
  VSS(64)  = GND
  DQ(38)  = M_D_DQ<38>
  VSS(63)  = GND
  DQ(34)  = M_D_DQ<34>
  VSS(62)  = GND
  DQ(44)  = M_D_DQ<44>
  VSS(61)  = GND
  DQ(40)  = M_D_DQ<40>
  VSS(60)  = GND
  DQS14P  = M_D_DQS_DP<14>
  DQS14N  = M_D_DQS_DN<14>
  VSS(59)  = GND
  DQ(46)  = M_D_DQ<46>
  VSS(58)  = GND
  DQ(42)  = M_D_DQ<42>
  VSS(57)  = GND
  DQ(52)  = M_D_DQ<52>
  VSS(56)  = GND
  DQ(48)  = M_D_DQ<48>
  VSS(55)  = GND
  DQS15P  = M_D_DQS_DP<15>
  DQS15N  = M_D_DQS_DN<15>
  VSS(54)  = GND
  DQ(54)  = M_D_DQ<54>
  VSS(53)  = GND
  DQ(50)  = M_D_DQ<50>
  VSS(52)  = GND
  DQ(60)  = M_D_DQ<60>
  VSS(51)  = GND
  DQ(56)  = M_D_DQ<56>
  VSS(50)  = GND
  DQS16P  = M_D_DQS_DP<16>
  DQS16N  = M_D_DQS_DN<16>
  VSS(49)  = GND
  DQ(62)  = M_D_DQ<62>
  VSS(48)  = GND
  DQ(58)  = M_D_DQ<58>
  VSS(47)  = GND
  SA(0)  = PVPP_DEF
  SA(1)  = GND
  SCL  = SMB_DDR_DEF_VPP_SCL
  VPP(4)  = PVPP_DEF
  VPP(3)  = PVPP_DEF
  RFU(2)  = TP_CH_D_DIMM_D1_RFU_2
  \12v\(0)  = P12V_NVDIMM_DEF
  VREFCA  = M_D_VREF
  VSS(46)  = GND
  DQ(5)  = M_D_DQ<5>
  VSS(45)  = GND
  DQ(1)  = M_D_DQ<1>
  VSS(44)  = GND
  DQS0N  = M_D_DQS_DN<0>
  DQS0P  = M_D_DQS_DP<0>
  VSS(43)  = GND
  DQ(7)  = M_D_DQ<7>
  VSS(42)  = GND
  DQ(3)  = M_D_DQ<3>
  VSS(41)  = GND
  DQ(13)  = M_D_DQ<13>
  VSS(40)  = GND
  DQ(9)  = M_D_DQ<9>
  VSS(39)  = GND
  DQS1N  = M_D_DQS_DN<1>
  DQS1P  = M_D_DQS_DP<1>
  VSS(38)  = GND
  DQ(15)  = M_D_DQ<15>
  VSS(37)  = GND
  DQ(11)  = M_D_DQ<11>
  VSS(36)  = GND
  DQ(21)  = M_D_DQ<21>
  VSS(35)  = GND
  DQ(17)  = M_D_DQ<17>
  VSS(34)  = GND
  DQS2N  = M_D_DQS_DN<2>
  DQS2P  = M_D_DQS_DP<2>
  VSS(33)  = GND
  DQ(23)  = M_D_DQ<23>
  VSS(32)  = GND
  DQ(19)  = M_D_DQ<19>
  VSS(31)  = GND
  DQ(29)  = M_D_DQ<29>
  VSS(30)  = GND
  DQ(25)  = M_D_DQ<25>
  VSS(29)  = GND
  DQS3N  = M_D_DQS_DN<3>
  DQS3P  = M_D_DQS_DP<3>
  VSS(28)  = GND
  DQ(31)  = M_D_DQ<31>
  VSS(27)  = GND
  DQ(27)  = M_D_DQ<27>
  VSS(26)  = GND
  CB(5)  = M_D_ECC<5>
  VSS(25)  = GND
  CB(1)  = M_D_ECC<1>
  VSS(24)  = GND
  DQS8N  = M_D_DQS_DN<8>
  DQS8P  = M_D_DQS_DP<8>
  VSS(23)  = GND
  CB(7)  = M_D_ECC<7>
  VSS(22)  = GND
  CB(3)  = M_D_ECC<3>
  VSS(21)  = GND
  CKE(1)  = M_D_CKE<3>
  VDD(12)  = PVDDQ_DEF
  RFU(0)  = TP_CH_D_DIMM_D1_RFU_0
  VDD(11)  = PVDDQ_DEF
  BG(1)  = M_D_BG<1>
  ALERT_N  = M_D_ALERT_N
  VDD(10)  = PVDDQ_DEF
  A11  = M_D_MA<11>
  A7  = M_D_MA<7>
  VDD(9)  = PVDDQ_DEF
  A5  = M_D_MA<5>
  A4  = M_D_MA<4>
  VDD(8)  = PVDDQ_DEF
  A2  = M_D_MA<2>
  VDD(7)  = PVDDQ_DEF
  CK1P  = M_D_CLK_DP<3>
  CK1N  = M_D_CLK_DN<3>
  VDD(6)  = PVDDQ_DEF
  VTT(0)  = PVTT_DEF
  PAR  = M_D_PAR
  VDD(5)  = PVDDQ_DEF
  BA(1)  = M_D_BA<1>
  A10  = M_D_MA<10>
  VDD(4)  = PVDDQ_DEF
  RFU(1)  = TP_CH_D_DIMM_D1_RFU_1
  A14_WE_N  = M_D_MA<14>
  VDD(3)  = PVDDQ_DEF
  SAVE_N_NC  = FM_ADR_COMPLETE_DEF_N
  VDD(2)  = PVDDQ_DEF
  A13  = M_D_MA<13>
  VDD(1)  = PVDDQ_DEF
  A17  = M_D_MA<17>
  C(2)  = M_D_C<2>
  VDD(0)  = PVDDQ_DEF
  S3_N_C(1)  = M_D_CS_N<7>
  SA(2)  = GND
  VSS(20)  = GND
  DQ(37)  = M_D_DQ<37>
  VSS(19)  = GND
  DQ(33)  = M_D_DQ<33>
  VSS(18)  = GND
  DQS4N  = M_D_DQS_DN<4>
  DQS4P  = M_D_DQS_DP<4>
  VSS(17)  = GND
  DQ(39)  = M_D_DQ<39>
  VSS(16)  = GND
  DQ(35)  = M_D_DQ<35>
  VSS(15)  = GND
  DQ(45)  = M_D_DQ<45>
  VSS(14)  = GND
  DQ(41)  = M_D_DQ<41>
  VSS(13)  = GND
  DQS5N  = M_D_DQS_DN<5>
  DQS5P  = M_D_DQS_DP<5>
  VSS(12)  = GND
  DQ(47)  = M_D_DQ<47>
  VSS(11)  = GND
  DQ(43)  = M_D_DQ<43>
  VSS(10)  = GND
  DQ(53)  = M_D_DQ<53>
  VSS(9)  = GND
  DQ(49)  = M_D_DQ<49>
  VSS(8)  = GND
  DQS6N  = M_D_DQS_DN<6>
  DQS6P  = M_D_DQS_DP<6>
  VSS(7)  = GND
  DQ(55)  = M_D_DQ<55>
  VSS(6)  = GND
  DQ(51)  = M_D_DQ<51>
  VSS(5)  = GND
  DQ(61)  = M_D_DQ<61>
  VSS(4)  = GND
  DQ(57)  = M_D_DQ<57>
  VSS(3)  = GND
  DQS7N  = M_D_DQS_DN<7>
  DQS7P  = M_D_DQS_DP<7>
  VSS(2)  = GND
  DQ(63)  = M_D_DQ<63>
  VSS(1)  = GND
  DQ(59)  = M_D_DQ<59>
  VSS(0)  = GND
  VDDSPD  = PVPP_DEF
  SDA  = SMB_DDR_DEF_VPP_SDA
  VPP(1)  = PVPP_DEF
  VPP(0)  = PVPP_DEF
  VPP(2)  = PVPP_DEF

(kicad_pcb
	(version 20260206)
	(generator "pcbnew")
	(generator_version "10.0")
	(general
		(thickness 1.6)
		(legacy_teardrops no)
	)
	(paper "A4")
	(title_block
		(title "Wiwynn_Tioga_Pass_MB.brd")
		(comment 1 "Tioga Pass / footprint 3254 of 4770 (J6M1), pads 101-151 of 291")
	)
	(layers
		(0 "F.Cu" signal "TOP")
		(4 "In1.Cu" signal "L2GND")
		(6 "In2.Cu" signal "L3")
		(8 "In3.Cu" signal "L4GND")
		(10 "In4.Cu" signal "L5")
		(12 "In5.Cu" signal "L6GND")
		(14 "In6.Cu" signal "L7VCC")
		(16 "In7.Cu" signal "L8VCC")
		(18 "In8.Cu" signal "L9GND")
		(20 "In9.Cu" signal "L10")
		(22 "In10.Cu" signal "L11GND")
		(24 "In11.Cu" signal "L12")
		(26 "In12.Cu" signal "L13GND")
		(2 "B.Cu" signal "BOTTOM")
		(9 "F.Adhes" user "F.Adhesive")
		(11 "B.Adhes" user "B.Adhesive")
		(13 "F.Paste" user "Package Geometry/Pastemask Top")
		(15 "B.Paste" user "Package Geometry/Pastemask Bottom")
		(5 "F.SilkS" user "Ref Des/Silkscreen Top")
		(7 "B.SilkS" user "Ref Des/Silkscreen Bottom")
		(1 "F.Mask" user "Board Geometry/Soldermask Top")
		(3 "B.Mask" user "Board Geometry/Soldermask Bottom")
		(17 "Dwgs.User" user "User.Drawings")
		(19 "Cmts.User" user "User.Comments")
		(21 "Eco1.User" user "User.Eco1")
		(23 "Eco2.User" user "User.Eco2")
		(25 "Edge.Cuts" user "Board Geometry/Outline")
		(27 "Margin" user)
		(31 "F.CrtYd" user "Package Geometry/Place Bound Top")
		(29 "B.CrtYd" user "Package Geometry/Place Bound Bottom")
		(35 "F.Fab" user "Ref Des/Assembly Top")
		(33 "B.Fab" user "Ref Des/Assembly Bottom")
	)
	(footprint ""
		(layer "B.Cu")
		(at 194.700398 -132.876036 90)
		(property "Reference" "J6M1"
			(at 2.352548 37.96411 0)
			(unlocked yes)
			(layer "B.SilkS")
			(effects
				(font
					(size 0.7874 0.5842)
					(thickness 0.1524)
				)
				(justify left mirror)
			)
		)
		(property "Value" ""
			(at 0 0 90)
			(layer "B.Fab")
			(effects
				(font
					(size 1.27 1.27)
				)
				(justify mirror)
			)
		)
		(duplicate_pad_numbers_are_jumpers no)
		(pad "98" smd rect
			(at 0 87.54999 270)
			(size 1.8034 0.508)
			(layers "B.Cu" "B.Mask" "B.Paste")
			(net "GND")
		)
		(pad "99" smd rect
			(at 0 88.399874 270)
			(size 1.8034 0.508)
			(layers "B.Cu" "B.Mask" "B.Paste")
			(net "M_D_DQS_DP<13>")
		)
		(pad "100" smd rect
			(at 0 89.250012 270)
			(size 1.8034 0.508)
			(layers "B.Cu" "B.Mask" "B.Paste")
			(net "M_D_DQS_DN<13>")
		)
		(pad "101" smd rect
			(at 0 90.099896 270)
			(size 1.8034 0.508)
			(layers "B.Cu" "B.Mask" "B.Paste")
			(net "GND")
		)
		(pad "102" smd rect
			(at 0 90.950034 270)
			(size 1.8034 0.508)
			(layers "B.Cu" "B.Mask" "B.Paste")
			(net "M_D_DQ<38>")
		)
		(pad "103" smd rect
			(at 0 91.799918 270)
			(size 1.8034 0.508)
			(layers "B.Cu" "B.Mask" "B.Paste")
			(net "GND")
		)
		(pad "104" smd rect
			(at 0 92.650056 270)
			(size 1.8034 0.508)
			(layers "B.Cu" "B.Mask" "B.Paste")
			(net "M_D_DQ<34>")
		)
		(pad "105" smd rect
			(at 0 93.49994 270)
			(size 1.8034 0.508)
			(layers "B.Cu" "B.Mask" "B.Paste")
			(net "GND")
		)
		(pad "106" smd rect
			(at 0 94.350078 270)
			(size 1.8034 0.508)
			(layers "B.Cu" "B.Mask" "B.Paste")
			(net "M_D_DQ<44>")
		)
		(pad "107" smd rect
			(at 0 95.199962 270)
			(size 1.8034 0.508)
			(layers "B.Cu" "B.Mask" "B.Paste")
			(net "GND")
		)
		(pad "108" smd rect
			(at 0 96.0501 270)
			(size 1.8034 0.508)
			(layers "B.Cu" "B.Mask" "B.Paste")
			(net "M_D_DQ<40>")
		)
		(pad "109" smd rect
			(at 0 96.899984 270)
			(size 1.8034 0.508)
			(layers "B.Cu" "B.Mask" "B.Paste")
			(net "GND")
		)
		(pad "110" smd rect
			(at 0 97.750122 270)
			(size 1.8034 0.508)
			(layers "B.Cu" "B.Mask" "B.Paste")
			(net "M_D_DQS_DP<14>")
		)
		(pad "111" smd rect
			(at 0 98.600006 270)
			(size 1.8034 0.508)
			(layers "B.Cu" "B.Mask" "B.Paste")
			(net "M_D_DQS_DN<14>")
		)
		(pad "112" smd rect
			(at 0 99.44989 270)
			(size 1.8034 0.508)
			(layers "B.Cu" "B.Mask" "B.Paste")
			(net "GND")
		)
		(pad "113" smd rect
			(at 0 100.300028 270)
			(size 1.8034 0.508)
			(layers "B.Cu" "B.Mask" "B.Paste")
			(net "M_D_DQ<46>")
		)
		(pad "114" smd rect
			(at 0 101.149912 270)
			(size 1.8034 0.508)
			(layers "B.Cu" "B.Mask" "B.Paste")
			(net "GND")
		)
		(pad "115" smd rect
			(at 0 102.00005 270)
			(size 1.8034 0.508)
			(layers "B.Cu" "B.Mask" "B.Paste")
			(net "M_D_DQ<42>")
		)
		(pad "116" smd rect
			(at 0 102.849934 270)
			(size 1.8034 0.508)
			(layers "B.Cu" "B.Mask" "B.Paste")
			(net "GND")
		)
		(pad "117" smd rect
			(at 0 103.700072 270)
			(size 1.8034 0.508)
			(layers "B.Cu" "B.Mask" "B.Paste")
			(net "M_D_DQ<52>")
		)
		(pad "118" smd rect
			(at 0 104.549956 270)
			(size 1.8034 0.508)
			(layers "B.Cu" "B.Mask" "B.Paste")
			(net "GND")
		)
		(pad "119" smd rect
			(at 0 105.400094 270)
			(size 1.8034 0.508)
			(layers "B.Cu" "B.Mask" "B.Paste")
			(net "M_D_DQ<48>")
		)
		(pad "120" smd rect
			(at 0 106.249978 270)
			(size 1.8034 0.508)
			(layers "B.Cu" "B.Mask" "B.Paste")
			(net "GND")
		)
		(pad "121" smd rect
			(at 0 107.100116 270)
			(size 1.8034 0.508)
			(layers "B.Cu" "B.Mask" "B.Paste")
			(net "M_D_DQS_DP<15>")
		)
		(pad "122" smd rect
			(at 0 107.95 270)
			(size 1.8034 0.508)
			(layers "B.Cu" "B.Mask" "B.Paste")
			(net "M_D_DQS_DN<15>")
		)
		(pad "123" smd rect
			(at 0 108.799884 270)
			(size 1.8034 0.508)
			(layers "B.Cu" "B.Mask" "B.Paste")
			(net "GND")
		)
		(pad "124" smd rect
			(at 0 109.650022 270)
			(size 1.8034 0.508)
			(layers "B.Cu" "B.Mask" "B.Paste")
			(net "M_D_DQ<54>")
		)
		(pad "125" smd rect
			(at 0 110.499906 270)
			(size 1.8034 0.508)
			(layers "B.Cu" "B.Mask" "B.Paste")
			(net "GND")
		)
		(pad "126" smd rect
			(at 0 111.350044 270)
			(size 1.8034 0.508)
			(layers "B.Cu" "B.Mask" "B.Paste")
			(net "M_D_DQ<50>")
		)
		(pad "127" smd rect
			(at 0 112.199928 270)
			(size 1.8034 0.508)
			(layers "B.Cu" "B.Mask" "B.Paste")
			(net "GND")
		)
		(pad "128" smd rect
			(at 0 113.050066 270)
			(size 1.8034 0.508)
			(layers "B.Cu" "B.Mask" "B.Paste")
			(net "M_D_DQ<60>")
		)
		(pad "129" smd rect
			(at 0 113.89995 270)
			(size 1.8034 0.508)
			(layers "B.Cu" "B.Mask" "B.Paste")
			(net "GND")
		)
		(pad "130" smd rect
			(at 0 114.750088 270)
			(size 1.8034 0.508)
			(layers "B.Cu" "B.Mask" "B.Paste")
			(net "M_D_DQ<56>")
		)
		(pad "131" smd rect
			(at 0 115.599972 270)
			(size 1.8034 0.508)
			(layers "B.Cu" "B.Mask" "B.Paste")
			(net "GND")
		)
		(pad "132" smd rect
			(at 0 116.45011 270)
			(size 1.8034 0.508)
			(layers "B.Cu" "B.Mask" "B.Paste")
			(net "M_D_DQS_DP<16>")
		)
		(pad "133" smd rect
			(at 0 117.299994 270)
			(size 1.8034 0.508)
			(layers "B.Cu" "B.Mask" "B.Paste")
			(net "M_D_DQS_DN<16>")
		)
		(pad "134" smd rect
			(at 0 118.149878 270)
			(size 1.8034 0.508)
			(layers "B.Cu" "B.Mask" "B.Paste")
			(net "GND")
		)
		(pad "135" smd rect
			(at 0 119.000016 270)
			(size 1.8034 0.508)
			(layers "B.Cu" "B.Mask" "B.Paste")
			(net "M_D_DQ<62>")
		)
		(pad "136" smd rect
			(at 0 119.8499 270)
			(size 1.8034 0.508)
			(layers "B.Cu" "B.Mask" "B.Paste")
			(net "GND")
		)
		(pad "137" smd rect
			(at 0 120.700038 270)
			(size 1.8034 0.508)
			(layers "B.Cu" "B.Mask" "B.Paste")
			(net "M_D_DQ<58>")
		)
		(pad "138" smd rect
			(at 0 121.549922 270)
			(size 1.8034 0.508)
			(layers "B.Cu" "B.Mask" "B.Paste")
			(net "GND")
		)
		(pad "139" smd rect
			(at 0 122.40006 270)
			(size 1.8034 0.508)
			(layers "B.Cu" "B.Mask" "B.Paste")
			(net "PVPP_DEF")
		)
		(pad "140" smd rect
			(at 0 123.249944 270)
			(size 1.8034 0.508)
			(layers "B.Cu" "B.Mask" "B.Paste")
			(net "GND")
		)
		(pad "141" smd rect
			(at 0 124.100082 270)
			(size 1.8034 0.508)
			(layers "B.Cu" "B.Mask" "B.Paste")
			(net "SMB_DDR_DEF_VPP_SCL")
		)
		(pad "142" smd rect
			(at 0 124.949966 270)
			(size 1.8034 0.508)
			(layers "B.Cu" "B.Mask" "B.Paste")
			(net "PVPP_DEF")
		)
		(pad "143" smd rect
			(at 0 125.800104 270)
			(size 1.8034 0.508)
			(layers "B.Cu" "B.Mask" "B.Paste")
			(net "PVPP_DEF")
		)
		(pad "144" smd rect
			(at 0 126.649988 270)
			(size 1.8034 0.508)
			(layers "B.Cu" "B.Mask" "B.Paste")
			(net "TP_CH_D_DIMM_D1_RFU_2")
		)
		(pad "145" smd rect
			(at -4.59994 0 270)
			(size 1.8034 0.508)
			(layers "B.Cu" "B.Mask" "B.Paste")
			(net "P12V_NVDIMM_DEF")
		)
		(pad "146" smd rect
			(at -4.59994 0.849884 270)
			(size 1.8034 0.508)
			(layers "B.Cu" "B.Mask" "B.Paste")
			(net "M_D_VREF")
		)
		(pad "147" smd rect
			(at -4.59994 1.700022 270)
			(size 1.8034 0.508)
			(layers "B.Cu" "B.Mask" "B.Paste")
			(net "GND")
		)
		(pad "148" smd rect
			(at -4.59994 2.549906 270)
			(size 1.8034 0.508)
			(layers "B.Cu" "B.Mask" "B.Paste")
			(net "M_D_DQ<5>")
		)
	)
)
